# T6G (Grand Teton) — schematic netlist excerpt (pin names and nets, part order shuffled) for the footprints in the layout excerpt that follows; sources: Cadence DE-HDL packaged netlist, KiCad conversion of 04192023_DAF0TMB3IC0_F0TG_MB_C_brd_V02_OCP.brd

C6111  Q_CAP  0.1UF 25V 10% X7R  pkg 0402  page 179 : A = P1V2_CPU0_USB2_DVDD12 ; B = GND
C523  Q_CAP  0.1UF 10V 10% X7S  pkg C0201  page 279 : A = P0V9_CPU0_RT0_2A ; B = GND
C981  Q_CAP  4.7UF 6.3V 20% X6S  pkg 0402  page 301 : A = P0V9_CPU0_RT2_2A ; B = GND

(kicad_pcb
	(version 20260206)
	(generator "pcbnew")
	(generator_version "10.0")
	(general
		(thickness 1.6)
		(legacy_teardrops no)
	)
	(paper "A4")
	(title_block
		(title "04192023_DAF0TMB3IC0_F0TG_MB_C_brd_V02_OCP.brd")
		(comment 1 "Grand Teton / footprints 5187-5189 of 8354")
	)
	(layers
		(0 "F.Cu" signal "TOP")
		(4 "In1.Cu" signal "GND")
		(6 "In2.Cu" signal "IN1")
		(8 "In3.Cu" signal "GND1")
		(10 "In4.Cu" signal "IN2")
		(12 "In5.Cu" signal "GND2")
		(14 "In6.Cu" signal "IN3")
		(16 "In7.Cu" signal "GND3")
		(18 "In8.Cu" signal "VCC")
		(20 "In9.Cu" signal "VCC1")
		(22 "In10.Cu" signal "GND4")
		(24 "In11.Cu" signal "IN4")
		(26 "In12.Cu" signal "GND5")
		(28 "In13.Cu" signal "IN5")
		(30 "In14.Cu" signal "GND6")
		(32 "In15.Cu" signal "IN6")
		(34 "In16.Cu" signal "GND7")
		(2 "B.Cu" signal "BOTTOM")
		(9 "F.Adhes" user "F.Adhesive")
		(11 "B.Adhes" user "B.Adhesive")
		(13 "F.Paste" user "Package Geometry/Pastemask Top")
		(15 "B.Paste" user "Package Geometry/Pastemask Bottom")
		(5 "F.SilkS" user "Ref Des/Silkscreen Top")
		(7 "B.SilkS" user "Ref Des/Silkscreen Bottom")
		(1 "F.Mask" user "Board Geometry/Soldermask Top")
		(3 "B.Mask" user "Board Geometry/Soldermask Bottom")
		(17 "Dwgs.User" user "User.Drawings")
		(19 "Cmts.User" user "User.Comments")
		(21 "Eco1.User" user "User.Eco1")
		(23 "Eco2.User" user "User.Eco2")
		(25 "Edge.Cuts" user "Board Geometry/Outline")
		(27 "Margin" user)
		(31 "F.CrtYd" user "Package Geometry/Place Bound Top")
		(29 "B.CrtYd" user "Package Geometry/Place Bound Bottom")
		(35 "F.Fab" user "Ref Des/Assembly Top")
		(33 "B.Fab" user "Ref Des/Assembly Bottom")
	)
	(footprint ""
		(layer "B.Cu")
		(at 111.47806 -35.088068 90)
		(property "Reference" "C6111"
			(at 0 0 90)
			(layer "B.SilkS")
			(hide yes)
			(effects
				(font
					(size 1.27 1.27)
				)
				(justify mirror)
			)
		)
		(property "Value" ""
			(at 0 0 90)
			(layer "B.Fab")
			(effects
				(font
					(size 1.27 1.27)
				)
				(justify mirror)
			)
		)
		(duplicate_pad_numbers_are_jumpers no)
		(fp_line
			(start 0.7874 -0.4064)
			(end -0.7874 -0.4064)
			(stroke
				(width 0.1524)
				(type default)
			)
			(layer "B.SilkS")
		)
		(fp_line
			(start -0.7874 -0.4064)
			(end -0.7874 0.4064)
			(stroke
				(width 0.1524)
				(type default)
			)
			(layer "B.SilkS")
		)
		(fp_line
			(start 0.7874 0.4064)
			(end 0.7874 -0.4064)
			(stroke
				(width 0.1524)
				(type default)
			)
			(layer "B.SilkS")
		)
		(fp_line
			(start -0.7874 0.4064)
			(end 0.7874 0.4064)
			(stroke
				(width 0.1524)
				(type default)
			)
			(layer "B.SilkS")
		)
		(fp_line
			(start 0.67945 -0.305054)
			(end 0.12065 -0.305054)
			(stroke
				(width 0.1)
				(type default)
			)
			(layer "B.Fab")
		)
		(fp_line
			(start 0.12065 -0.305054)
			(end 0.12065 -0.2794)
			(stroke
				(width 0.1)
				(type default)
			)
			(layer "B.Fab")
		)
		(fp_line
			(start -0.12065 -0.3048)
			(end -0.67945 -0.3048)
			(stroke
				(width 0.1)
				(type default)
			)
			(layer "B.Fab")
		)
		(fp_line
			(start -0.67945 -0.3048)
			(end -0.67945 0.3048)
			(stroke
				(width 0.1)
				(type default)
			)
			(layer "B.Fab")
		)
		(fp_line
			(start 0.12065 -0.2794)
			(end -0.12065 -0.2794)
			(stroke
				(width 0.1)
				(type default)
			)
			(layer "B.Fab")
		)
		(fp_line
			(start -0.12065 -0.2794)
			(end -0.12065 -0.3048)
			(stroke
				(width 0.1)
				(type default)
			)
			(layer "B.Fab")
		)
		(fp_line
			(start 0.12065 0.2794)
			(end 0.12065 0.3048)
			(stroke
				(width 0.1)
				(type default)
			)
			(layer "B.Fab")
		)
		(fp_line
			(start -0.120396 0.2794)
			(end 0.12065 0.2794)
			(stroke
				(width 0.1)
				(type default)
			)
			(layer "B.Fab")
		)
		(fp_line
			(start 0.67945 0.3048)
			(end 0.67945 -0.305054)
			(stroke
				(width 0.1)
				(type default)
			)
			(layer "B.Fab")
		)
		(fp_line
			(start 0.12065 0.3048)
			(end 0.67945 0.3048)
			(stroke
				(width 0.1)
				(type default)
			)
			(layer "B.Fab")
		)
		(fp_line
			(start -0.120396 0.3048)
			(end -0.120396 0.2794)
			(stroke
				(width 0.1)
				(type default)
			)
			(layer "B.Fab")
		)
		(fp_line
			(start -0.67945 0.3048)
			(end -0.120396 0.3048)
			(stroke
				(width 0.1)
				(type default)
			)
			(layer "B.Fab")
		)
		(pad "1" smd circle
			(at 0.40005 0 270)
			(size 0 0)
			(layers "B.Cu" "B.Mask" "B.Paste")
			(net "P1V2_CPU0_USB2_DVDD12")
		)
		(pad "2" smd circle
			(at -0.40005 0 270)
			(size 0 0)
			(layers "B.Cu" "B.Mask" "B.Paste")
			(net "GND")
		)
	)
	(footprint ""
		(layer "B.Cu")
		(at 304.718212 -396.393162 -90)
		(property "Reference" "C523"
			(at 0 0 90)
			(layer "B.SilkS")
			(hide yes)
			(effects
				(font
					(size 1.27 1.27)
				)
				(justify mirror)
			)
		)
		(property "Value" ""
			(at 0 0 90)
			(layer "B.Fab")
			(effects
				(font
					(size 1.27 1.27)
				)
				(justify mirror)
			)
		)
		(duplicate_pad_numbers_are_jumpers no)
		(fp_line
			(start -0.299974 0.150114)
			(end 0.299974 0.150114)
			(stroke
				(width 0.1)
				(type default)
			)
			(layer "B.Fab")
		)
		(fp_line
			(start 0.299974 0.150114)
			(end 0.299974 -0.150114)
			(stroke
				(width 0.1)
				(type default)
			)
			(layer "B.Fab")
		)
		(fp_line
			(start -0.299974 -0.150114)
			(end -0.299974 0.150114)
			(stroke
				(width 0.1)
				(type default)
			)
			(layer "B.Fab")
		)
		(fp_line
			(start 0.299974 -0.150114)
			(end -0.299974 -0.150114)
			(stroke
				(width 0.1)
				(type default)
			)
			(layer "B.Fab")
		)
		(pad "1" smd rect
			(at 0.2667 0 90)
			(size 0.3048 0.381)
			(layers "B.Cu" "B.Mask" "B.Paste")
			(net "P0V9_CPU0_RT0_2A")
		)
		(pad "2" smd rect
			(at -0.2667 0 90)
			(size 0.3048 0.381)
			(layers "B.Cu" "B.Mask" "B.Paste")
			(net "GND")
		)
	)
	(footprint ""
		(layer "B.Cu")
		(at 416.218878 -398.942052 90)
		(property "Reference" "C981"
			(at 0 0 90)
			(layer "B.SilkS")
			(hide yes)
			(effects
				(font
					(size 1.27 1.27)
				)
				(justify mirror)
			)
		)
		(property "Value" ""
			(at 0 0 90)
			(layer "B.Fab")
			(effects
				(font
					(size 1.27 1.27)
				)
				(justify mirror)
			)
		)
		(duplicate_pad_numbers_are_jumpers no)
		(fp_line
			(start 0.7874 -0.4064)
			(end -0.7874 -0.4064)
			(stroke
				(width 0.1524)
				(type default)
			)
			(layer "B.SilkS")
		)
		(fp_line
			(start -0.7874 -0.4064)
			(end -0.7874 0.4064)
			(stroke
				(width 0.1524)
				(type default)
			)
			(layer "B.SilkS")
		)
		(fp_line
			(start 0.7874 0.4064)
			(end 0.7874 -0.4064)
			(stroke
				(width 0.1524)
				(type default)
			)
			(layer "B.SilkS")
		)
		(fp_line
			(start -0.7874 0.4064)
			(end 0.7874 0.4064)
			(stroke
				(width 0.1524)
				(type default)
			)
			(layer "B.SilkS")
		)
		(fp_line
			(start 0.67945 -0.305054)
			(end 0.12065 -0.305054)
			(stroke
				(width 0.1)
				(type default)
			)
			(layer "B.Fab")
		)
		(fp_line
			(start 0.12065 -0.305054)
			(end 0.12065 -0.2794)
			(stroke
				(width 0.1)
				(type default)
			)
			(layer "B.Fab")
		)
		(fp_line
			(start -0.12065 -0.3048)
			(end -0.67945 -0.3048)
			(stroke
				(width 0.1)
				(type default)
			)
			(layer "B.Fab")
		)
		(fp_line
			(start -0.67945 -0.3048)
			(end -0.67945 0.3048)
			(stroke
				(width 0.1)
				(type default)
			)
			(layer "B.Fab")
		)
		(fp_line
			(start 0.12065 -0.2794)
			(end -0.12065 -0.2794)
			(stroke
				(width 0.1)
				(type default)
			)
			(layer "B.Fab")
		)
		(fp_line
			(start -0.12065 -0.2794)
			(end -0.12065 -0.3048)
			(stroke
				(width 0.1)
				(type default)
			)
			(layer "B.Fab")
		)
		(fp_line
			(start 0.12065 0.2794)
			(end 0.12065 0.3048)
			(stroke
				(width 0.1)
				(type default)
			)
			(layer "B.Fab")
		)
		(fp_line
			(start -0.120396 0.2794)
			(end 0.12065 0.2794)
			(stroke
				(width 0.1)
				(type default)
			)
			(layer "B.Fab")
		)
		(fp_line
			(start 0.67945 0.3048)
			(end 0.67945 -0.305054)
			(stroke
				(width 0.1)
				(type default)
			)
			(layer "B.Fab")
		)
		(fp_line
			(start 0.12065 0.3048)
			(end 0.67945 0.3048)
			(stroke
				(width 0.1)
				(type default)
			)
			(layer "B.Fab")
		)
		(fp_line
			(start -0.120396 0.3048)
			(end -0.120396 0.2794)
			(stroke
				(width 0.1)
				(type default)
			)
			(layer "B.Fab")
		)
		(fp_line
			(start -0.67945 0.3048)
			(end -0.120396 0.3048)
			(stroke
				(width 0.1)
				(type default)
			)
			(layer "B.Fab")
		)
		(pad "1" smd circle
			(at 0.40005 0 270)
			(size 0 0)
			(layers "B.Cu" "B.Mask" "B.Paste")
			(net "P0V9_CPU0_RT2_2A")
		)
		(pad "2" smd circle
			(at -0.40005 0 270)
			(size 0 0)
			(layers "B.Cu" "B.Mask" "B.Paste")
			(net "GND")
		)
	)
)
